(kicad_pcb
	(version 20260206)
	(generator "pcbnew")
	(generator_version "10.0")
	(general
		(thickness 1.6)
		(legacy_teardrops no)
	)
	(paper "A4")
	(title_block
		(title "03242023_DA0F0TMBIJ0_F0T_Motherboard_J_brd_V01_OCP.brd")
		(comment 1 "Grand Teton / footprint 3039 of 6105 (U2), pads 4108-4215 of 4677")
	)
	(layers
		(0 "F.Cu" signal "TOP")
		(4 "In1.Cu" signal "GND")
		(6 "In2.Cu" signal "IN1")
		(8 "In3.Cu" signal "GND1")
		(10 "In4.Cu" signal "IN2")
		(12 "In5.Cu" signal "GND2")
		(14 "In6.Cu" signal "IN3")
		(16 "In7.Cu" signal "GND3")
		(18 "In8.Cu" signal "VCC")
		(20 "In9.Cu" signal "VCC1")
		(22 "In10.Cu" signal "GND4")
		(24 "In11.Cu" signal "IN4")
		(26 "In12.Cu" signal "GND5")
		(28 "In13.Cu" signal "IN5")
		(30 "In14.Cu" signal "GND6")
		(32 "In15.Cu" signal "IN6")
		(34 "In16.Cu" signal "GND7")
		(2 "B.Cu" signal "BOTTOM")
		(9 "F.Adhes" user "F.Adhesive")
		(11 "B.Adhes" user "B.Adhesive")
		(13 "F.Paste" user "Package Geometry/Pastemask Top")
		(15 "B.Paste" user "Package Geometry/Pastemask Bottom")
		(5 "F.SilkS" user "Ref Des/Silkscreen Top")
		(7 "B.SilkS" user "Ref Des/Silkscreen Bottom")
		(1 "F.Mask" user "Board Geometry/Soldermask Top")
		(3 "B.Mask" user "Board Geometry/Soldermask Bottom")
		(17 "Dwgs.User" user "User.Drawings")
		(19 "Cmts.User" user "User.Comments")
		(21 "Eco1.User" user "User.Eco1")
		(23 "Eco2.User" user "User.Eco2")
		(25 "Edge.Cuts" user "Board Geometry/Outline")
		(27 "Margin" user)
		(31 "F.CrtYd" user "Package Geometry/Place Bound Top")
		(29 "B.CrtYd" user "Package Geometry/Place Bound Bottom")
		(35 "F.Fab" user "Ref Des/Assembly Top")
		(33 "B.Fab" user "Ref Des/Assembly Bottom")
	)
	(footprint ""
		(layer "F.Cu")
		(at 359.870248 -251.76988 90)
		(property "Reference" "U2"
			(at -74.416158 -44.488608 0)
			(unlocked yes)
			(layer "F.SilkS")
			(effects
				(font
					(size 1.6002 1.1938)
					(thickness 0.1524)
				)
				(justify left)
			)
		)
		(property "Value" ""
			(at 0 0 90)
			(layer "F.Fab")
			(effects
				(font
					(size 1.27 1.27)
				)
			)
		)
		(duplicate_pad_numbers_are_jumpers no)
		(pad "H22" smd circle
			(at -20.333462 -23.784814 270)
			(size 0.4318 0.4318)
			(layers "F.Cu" "F.Mask" "F.Paste")
			(net "GND")
		)
		(pad "H24" smd circle
			(at -18.705576 -23.784814 270)
			(size 0.4318 0.4318)
			(layers "F.Cu" "F.Mask" "F.Paste")
			(net "M_B_CPU0_SB_DQS_DN<1>")
		)
		(pad "H26" smd circle
			(at -17.07769 -23.784814 270)
			(size 0.4318 0.4318)
			(layers "F.Cu" "F.Mask" "F.Paste")
			(net "GND")
		)
		(pad "H28" smd circle
			(at -15.450058 -23.784814 270)
			(size 0.4318 0.4318)
			(layers "F.Cu" "F.Mask" "F.Paste")
			(net "GND")
		)
		(pad "H30" smd circle
			(at -13.822426 -23.784814 270)
			(size 0.4318 0.4318)
			(layers "F.Cu" "F.Mask" "F.Paste")
			(net "M_A_CPU0_SB_DQS_DN<0>")
		)
		(pad "H32" smd circle
			(at -12.19454 -23.784814 270)
			(size 0.4318 0.4318)
			(layers "F.Cu" "F.Mask" "F.Paste")
			(net "GND")
		)
		(pad "H34" smd circle
			(at -10.566654 -23.784814 270)
			(size 0.4318 0.4318)
			(layers "F.Cu" "F.Mask" "F.Paste")
			(net "GND")
		)
		(pad "H36" smd circle
			(at -8.939022 -23.784814 270)
			(size 0.4318 0.4318)
			(layers "F.Cu" "F.Mask" "F.Paste")
			(net "M_B_CPU0_SB_DQS_DP<9>")
		)
		(pad "H38" smd circle
			(at -7.311136 -23.784814 270)
			(size 0.4318 0.4318)
			(layers "F.Cu" "F.Mask" "F.Paste")
			(net "GND")
		)
		(pad "H40" smd circle
			(at -5.68325 -23.784814 270)
			(size 0.4318 0.4318)
			(layers "F.Cu" "F.Mask" "F.Paste")
			(net "GND")
		)
		(pad "H42" smd circle
			(at -4.055618 -23.784814 270)
			(size 0.4318 0.4318)
			(layers "F.Cu" "F.Mask" "F.Paste")
			(net "M_B_CPU0_SB_CA<6>")
		)
		(pad "H44" smd circle
			(at -2.427732 -23.784814 270)
			(size 0.4318 0.4318)
			(layers "F.Cu" "F.Mask" "F.Paste")
			(net "GND")
		)
		(pad "H47" smd circle
			(at 1.613916 -23.675086 270)
			(size 0.4318 0.4318)
			(layers "F.Cu" "F.Mask" "F.Paste")
			(net "GND")
		)
		(pad "H49" smd circle
			(at 3.241802 -23.675086 270)
			(size 0.4318 0.4318)
			(layers "F.Cu" "F.Mask" "F.Paste")
			(net "M_B_CPU0_SA_CA<0>")
		)
		(pad "H51" smd circle
			(at 4.869434 -23.675086 270)
			(size 0.4318 0.4318)
			(layers "F.Cu" "F.Mask" "F.Paste")
			(net "GND")
		)
		(pad "H53" smd circle
			(at 6.49732 -23.675086 270)
			(size 0.4318 0.4318)
			(layers "F.Cu" "F.Mask" "F.Paste")
			(net "GND")
		)
		(pad "H55" smd circle
			(at 8.124952 -23.675086 270)
			(size 0.4318 0.4318)
			(layers "F.Cu" "F.Mask" "F.Paste")
			(net "M_B_CPU0_SA_DQS_DN<4>")
		)
		(pad "H57" smd circle
			(at 9.752838 -23.675086 270)
			(size 0.4318 0.4318)
			(layers "F.Cu" "F.Mask" "F.Paste")
			(net "GND")
		)
		(pad "H59" smd circle
			(at 11.380724 -23.675086 270)
			(size 0.4318 0.4318)
			(layers "F.Cu" "F.Mask" "F.Paste")
			(net "GND")
		)
		(pad "H61" smd circle
			(at 13.008356 -23.675086 270)
			(size 0.4318 0.4318)
			(layers "F.Cu" "F.Mask" "F.Paste")
			(net "M_B_CPU0_SA_DQS_DN<2>")
		)
		(pad "H63" smd circle
			(at 14.635988 -23.675086 270)
			(size 0.4318 0.4318)
			(layers "F.Cu" "F.Mask" "F.Paste")
			(net "GND")
		)
		(pad "H65" smd circle
			(at 16.263874 -23.675086 270)
			(size 0.4318 0.4318)
			(layers "F.Cu" "F.Mask" "F.Paste")
			(net "GND")
		)
		(pad "H67" smd circle
			(at 17.89176 -23.675086 270)
			(size 0.4318 0.4318)
			(layers "F.Cu" "F.Mask" "F.Paste")
			(net "M_A_CPU0_SA_DQS_DN<1>")
		)
		(pad "H69" smd circle
			(at 19.519392 -23.675086 270)
			(size 0.4318 0.4318)
			(layers "F.Cu" "F.Mask" "F.Paste")
			(net "GND")
		)
		(pad "H71" smd circle
			(at 21.147278 -23.675086 270)
			(size 0.4318 0.4318)
			(layers "F.Cu" "F.Mask" "F.Paste")
			(net "GND")
		)
		(pad "H73" smd circle
			(at 22.77491 -23.675086 270)
			(size 0.4318 0.4318)
			(layers "F.Cu" "F.Mask" "F.Paste")
			(net "M_B_CPU0_SA_DQS_DN<0>")
		)
		(pad "H75" smd circle
			(at 24.402796 -23.675086 270)
			(size 0.4318 0.4318)
			(layers "F.Cu" "F.Mask" "F.Paste")
			(net "GND")
		)
		(pad "H77" smd circle
			(at 26.030682 -23.675086 270)
			(size 0.4318 0.4318)
			(layers "F.Cu" "F.Mask" "F.Paste")
			(net "M_A_CPU0_SA_DQS_DN<5>")
		)
		(pad "H79" smd circle
			(at 27.658314 -23.675086 270)
			(size 0.4318 0.4318)
			(layers "F.Cu" "F.Mask" "F.Paste")
			(net "GND")
		)
		(pad "H81" smd circle
			(at 29.2862 -23.675086 270)
			(size 0.4318 0.4318)
			(layers "F.Cu" "F.Mask" "F.Paste")
			(net "GND")
		)
		(pad "H83" smd circle
			(at 30.914086 -23.675086 270)
			(size 0.4318 0.4318)
			(layers "F.Cu" "F.Mask" "F.Paste")
			(net "UPI_CPU1_CPU0_P2P2_DP<21>")
		)
		(pad "H85" smd circle
			(at 32.541718 -23.675086 270)
			(size 0.4318 0.4318)
			(layers "F.Cu" "F.Mask" "F.Paste")
			(net "UPI_CPU0_CPU1_P2P2_DN<19>")
		)
		(pad "H87" smd circle
			(at 34.169604 -23.675086 270)
			(size 0.4318 0.4318)
			(layers "F.Cu" "F.Mask" "F.Paste")
			(net "UPI_CPU0_CPU1_P2P2_DP<20>")
		)
		(pad "H89" smd oval
			(at 35.797236 -23.675086 45)
			(size 0.381 0.4826)
			(drill
				(offset 0 -0.0508)
			)
			(layers "F.Cu" "F.Mask" "F.Paste")
			(net "PVCCFA_EHV_FIVRA_CPU0")
		)
		(pad "J3" smd oval
			(at -35.797236 -23.314914 135)
			(size 0.381 0.4826)
			(drill
				(offset 0 -0.0508)
			)
			(layers "F.Cu" "F.Mask" "F.Paste")
			(net "UPI_CPU0_CPU1_P0P1_DP<0>")
		)
		(pad "J5" smd circle
			(at -34.169604 -23.314914 270)
			(size 0.4318 0.4318)
			(layers "F.Cu" "F.Mask" "F.Paste")
			(net "GND")
		)
		(pad "J7" smd circle
			(at -32.541718 -23.314914 270)
			(size 0.4318 0.4318)
			(layers "F.Cu" "F.Mask" "F.Paste")
			(net "PVCCFA_EHV_FIVRA_CPU0")
		)
		(pad "J9" smd circle
			(at -30.914086 -23.314914 270)
			(size 0.4318 0.4318)
			(layers "F.Cu" "F.Mask" "F.Paste")
			(net "GND")
		)
		(pad "J11" smd circle
			(at -29.2862 -23.314914 270)
			(size 0.4318 0.4318)
			(layers "F.Cu" "F.Mask" "F.Paste")
			(net "PVCCFA_EHV_FIVRA_CPU0")
		)
		(pad "J13" smd circle
			(at -27.658314 -23.314914 270)
			(size 0.4318 0.4318)
			(layers "F.Cu" "F.Mask" "F.Paste")
			(net "TP_CPU0_PPD")
		)
		(pad "J15" smd circle
			(at -26.030682 -23.314914 270)
			(size 0.4318 0.4318)
			(layers "F.Cu" "F.Mask" "F.Paste")
			(net "GND")
		)
		(pad "J17" smd circle
			(at -24.402796 -23.314914 270)
			(size 0.4318 0.4318)
			(layers "F.Cu" "F.Mask" "F.Paste")
			(net "M_B_CPU0_SB_DQ<20>")
		)
		(pad "J19" smd circle
			(at -22.77491 -23.314914 270)
			(size 0.4318 0.4318)
			(layers "F.Cu" "F.Mask" "F.Paste")
			(net "M_B_CPU0_SB_DQ<17>")
		)
		(pad "J21" smd circle
			(at -21.147278 -23.314914 270)
			(size 0.4318 0.4318)
			(layers "F.Cu" "F.Mask" "F.Paste")
			(net "GND")
		)
		(pad "J23" smd circle
			(at -19.519392 -23.314914 270)
			(size 0.4318 0.4318)
			(layers "F.Cu" "F.Mask" "F.Paste")
			(net "M_B_CPU0_SB_DQ<12>")
		)
		(pad "J25" smd circle
			(at -17.89176 -23.314914 270)
			(size 0.4318 0.4318)
			(layers "F.Cu" "F.Mask" "F.Paste")
			(net "M_B_CPU0_SB_DQ<9>")
		)
		(pad "J27" smd circle
			(at -16.263874 -23.314914 270)
			(size 0.4318 0.4318)
			(layers "F.Cu" "F.Mask" "F.Paste")
			(net "GND")
		)
		(pad "J29" smd circle
			(at -14.635988 -23.314914 270)
			(size 0.4318 0.4318)
			(layers "F.Cu" "F.Mask" "F.Paste")
			(net "M_A_CPU0_SB_DQ<4>")
		)
		(pad "J31" smd circle
			(at -13.008356 -23.314914 270)
			(size 0.4318 0.4318)
			(layers "F.Cu" "F.Mask" "F.Paste")
			(net "M_A_CPU0_SB_DQ<1>")
		)
		(pad "J33" smd circle
			(at -11.380724 -23.314914 270)
			(size 0.4318 0.4318)
			(layers "F.Cu" "F.Mask" "F.Paste")
			(net "GND")
		)
		(pad "J35" smd circle
			(at -9.752838 -23.314914 270)
			(size 0.4318 0.4318)
			(layers "F.Cu" "F.Mask" "F.Paste")
			(net "M_B_CPU0_SB_CB<0>")
		)
		(pad "J37" smd circle
			(at -8.124952 -23.314914 270)
			(size 0.4318 0.4318)
			(layers "F.Cu" "F.Mask" "F.Paste")
			(net "M_B_CPU0_SB_CB<5>")
		)
		(pad "J39" smd circle
			(at -6.49732 -23.314914 270)
			(size 0.4318 0.4318)
			(layers "F.Cu" "F.Mask" "F.Paste")
			(net "GND")
		)
		(pad "J41" smd circle
			(at -4.869434 -23.314914 270)
			(size 0.4318 0.4318)
			(layers "F.Cu" "F.Mask" "F.Paste")
			(net "M_B_CPU0_SB_CS_N<0>")
		)
		(pad "J43" smd circle
			(at -3.241802 -23.314914 270)
			(size 0.4318 0.4318)
			(layers "F.Cu" "F.Mask" "F.Paste")
			(net "M_B_CPU0_SB_CA<4>")
		)
		(pad "J45" smd circle
			(at -1.613916 -23.314914 270)
			(size 0.4318 0.4318)
			(layers "F.Cu" "F.Mask" "F.Paste")
			(net "GND")
		)
		(pad "J48" smd circle
			(at 2.427732 -23.204932 270)
			(size 0.4318 0.4318)
			(layers "F.Cu" "F.Mask" "F.Paste")
			(net "M_B_CPU0_SA_CA<2>")
		)
		(pad "J50" smd circle
			(at 4.055618 -23.204932 270)
			(size 0.4318 0.4318)
			(layers "F.Cu" "F.Mask" "F.Paste")
			(net "M_B_CPU0_SA_CS_N<1>")
		)
		(pad "J52" smd circle
			(at 5.68325 -23.204932 270)
			(size 0.4318 0.4318)
			(layers "F.Cu" "F.Mask" "F.Paste")
			(net "GND")
		)
		(pad "J54" smd circle
			(at 7.311136 -23.204932 270)
			(size 0.4318 0.4318)
			(layers "F.Cu" "F.Mask" "F.Paste")
			(net "M_B_CPU0_SA_CB<4>")
		)
		(pad "J56" smd circle
			(at 8.939022 -23.204932 270)
			(size 0.4318 0.4318)
			(layers "F.Cu" "F.Mask" "F.Paste")
			(net "M_B_CPU0_SA_CB<1>")
		)
		(pad "J58" smd circle
			(at 10.566654 -23.204932 270)
			(size 0.4318 0.4318)
			(layers "F.Cu" "F.Mask" "F.Paste")
			(net "GND")
		)
		(pad "J60" smd circle
			(at 12.19454 -23.204932 270)
			(size 0.4318 0.4318)
			(layers "F.Cu" "F.Mask" "F.Paste")
			(net "M_B_CPU0_SA_DQ<20>")
		)
		(pad "J62" smd circle
			(at 13.822426 -23.204932 270)
			(size 0.4318 0.4318)
			(layers "F.Cu" "F.Mask" "F.Paste")
			(net "M_B_CPU0_SA_DQ<17>")
		)
		(pad "J64" smd circle
			(at 15.450058 -23.204932 270)
			(size 0.4318 0.4318)
			(layers "F.Cu" "F.Mask" "F.Paste")
			(net "GND")
		)
		(pad "J66" smd circle
			(at 17.07769 -23.204932 270)
			(size 0.4318 0.4318)
			(layers "F.Cu" "F.Mask" "F.Paste")
			(net "M_A_CPU0_SA_DQ<12>")
		)
		(pad "J68" smd circle
			(at 18.705576 -23.204932 270)
			(size 0.4318 0.4318)
			(layers "F.Cu" "F.Mask" "F.Paste")
			(net "M_A_CPU0_SA_DQ<9>")
		)
		(pad "J70" smd circle
			(at 20.333462 -23.204932 270)
			(size 0.4318 0.4318)
			(layers "F.Cu" "F.Mask" "F.Paste")
			(net "GND")
		)
		(pad "J72" smd circle
			(at 21.961094 -23.204932 270)
			(size 0.4318 0.4318)
			(layers "F.Cu" "F.Mask" "F.Paste")
			(net "M_B_CPU0_SA_DQ<4>")
		)
		(pad "J74" smd circle
			(at 23.58898 -23.204932 270)
			(size 0.4318 0.4318)
			(layers "F.Cu" "F.Mask" "F.Paste")
			(net "M_B_CPU0_SA_DQ<1>")
		)
		(pad "J76" smd circle
			(at 25.216612 -23.204932 270)
			(size 0.4318 0.4318)
			(layers "F.Cu" "F.Mask" "F.Paste")
			(net "GND")
		)
		(pad "J78" smd circle
			(at 26.844498 -23.204932 270)
			(size 0.4318 0.4318)
			(layers "F.Cu" "F.Mask" "F.Paste")
			(net "GND")
		)
		(pad "J80" smd circle
			(at 28.472384 -23.204932 270)
			(size 0.4318 0.4318)
			(layers "F.Cu" "F.Mask" "F.Paste")
			(net "PVCCFA_EHV_FIVRA_CPU0")
		)
		(pad "J82" smd circle
			(at 30.100016 -23.204932 270)
			(size 0.4318 0.4318)
			(layers "F.Cu" "F.Mask" "F.Paste")
			(net "UPI_CPU1_CPU0_P2P2_DN<19>")
		)
		(pad "J84" smd circle
			(at 31.727902 -23.204932 270)
			(size 0.4318 0.4318)
			(layers "F.Cu" "F.Mask" "F.Paste")
			(net "GND")
		)
		(pad "J86" smd circle
			(at 33.355534 -23.204932 270)
			(size 0.4318 0.4318)
			(layers "F.Cu" "F.Mask" "F.Paste")
			(net "GND")
		)
		(pad "J88" smd circle
			(at 34.98342 -23.204932 270)
			(size 0.4318 0.4318)
			(layers "F.Cu" "F.Mask" "F.Paste")
			(net "GND")
		)
		(pad "J90" smd oval
			(at 36.611306 -23.204932 45)
			(size 0.381 0.4826)
			(drill
				(offset 0 -0.0508)
			)
			(layers "F.Cu" "F.Mask" "F.Paste")
			(net "P5E_CPU0_PE4_RX_DN<0>")
		)
		(pad "K2" smd oval
			(at -36.611306 -22.845268 135)
			(size 0.381 0.4826)
			(drill
				(offset 0 -0.0508)
			)
			(layers "F.Cu" "F.Mask" "F.Paste")
			(net "GND")
		)
		(pad "K4" smd circle
			(at -34.98342 -22.845268 270)
			(size 0.4318 0.4318)
			(layers "F.Cu" "F.Mask" "F.Paste")
			(net "UPI_CPU0_CPU1_P0P1_DN<0>")
		)
		(pad "K6" smd circle
			(at -33.355534 -22.845268 270)
			(size 0.4318 0.4318)
			(layers "F.Cu" "F.Mask" "F.Paste")
			(net "UPI_CPU1_CPU0_P1P0_DN<0>")
		)
		(pad "K8" smd circle
			(at -31.727902 -22.845268 270)
			(size 0.4318 0.4318)
			(layers "F.Cu" "F.Mask" "F.Paste")
			(net "GND")
		)
		(pad "K10" smd circle
			(at -30.100016 -22.845268 270)
			(size 0.4318 0.4318)
			(layers "F.Cu" "F.Mask" "F.Paste")
			(net "P5E_CPU0_PE0_RX_DN<0>")
		)
		(pad "K12" smd circle
			(at -28.472384 -22.845268 270)
			(size 0.4318 0.4318)
			(layers "F.Cu" "F.Mask" "F.Paste")
			(net "GND")
		)
		(pad "K14" smd circle
			(at -26.844498 -22.845268 270)
			(size 0.4318 0.4318)
			(layers "F.Cu" "F.Mask" "F.Paste")
			(net "GND")
		)
		(pad "K16" smd circle
			(at -25.216612 -22.845268 270)
			(size 0.4318 0.4318)
			(layers "F.Cu" "F.Mask" "F.Paste")
			(net "M_B_CPU0_SB_DQ<21>")
		)
		(pad "K18" smd circle
			(at -23.58898 -22.845268 270)
			(size 0.4318 0.4318)
			(layers "F.Cu" "F.Mask" "F.Paste")
			(net "M_B_CPU0_SB_DQS_DP<2>")
		)
		(pad "K20" smd circle
			(at -21.961094 -22.845268 270)
			(size 0.4318 0.4318)
			(layers "F.Cu" "F.Mask" "F.Paste")
			(net "M_B_CPU0_SB_DQ<16>")
		)
		(pad "K22" smd circle
			(at -20.333462 -22.845268 270)
			(size 0.4318 0.4318)
			(layers "F.Cu" "F.Mask" "F.Paste")
			(net "M_B_CPU0_SB_DQ<13>")
		)
		(pad "K24" smd circle
			(at -18.705576 -22.845268 270)
			(size 0.4318 0.4318)
			(layers "F.Cu" "F.Mask" "F.Paste")
			(net "M_B_CPU0_SB_DQS_DP<1>")
		)
		(pad "K26" smd circle
			(at -17.07769 -22.845268 270)
			(size 0.4318 0.4318)
			(layers "F.Cu" "F.Mask" "F.Paste")
			(net "M_B_CPU0_SB_DQ<8>")
		)
		(pad "K28" smd circle
			(at -15.450058 -22.845268 270)
			(size 0.4318 0.4318)
			(layers "F.Cu" "F.Mask" "F.Paste")
			(net "M_A_CPU0_SB_DQ<5>")
		)
		(pad "K30" smd circle
			(at -13.822426 -22.845268 270)
			(size 0.4318 0.4318)
			(layers "F.Cu" "F.Mask" "F.Paste")
			(net "M_A_CPU0_SB_DQS_DP<0>")
		)
		(pad "K32" smd circle
			(at -12.19454 -22.845268 270)
			(size 0.4318 0.4318)
			(layers "F.Cu" "F.Mask" "F.Paste")
			(net "M_A_CPU0_SB_DQ<0>")
		)
		(pad "K34" smd circle
			(at -10.566654 -22.845268 270)
			(size 0.4318 0.4318)
			(layers "F.Cu" "F.Mask" "F.Paste")
			(net "M_B_CPU0_SB_CB<1>")
		)
		(pad "K36" smd circle
			(at -8.939022 -22.845268 270)
			(size 0.4318 0.4318)
			(layers "F.Cu" "F.Mask" "F.Paste")
			(net "M_B_CPU0_SB_DQS_DN<9>")
		)
		(pad "K38" smd circle
			(at -7.311136 -22.845268 270)
			(size 0.4318 0.4318)
			(layers "F.Cu" "F.Mask" "F.Paste")
			(net "M_B_CPU0_SB_CB<4>")
		)
		(pad "K40" smd circle
			(at -5.68325 -22.845268 270)
			(size 0.4318 0.4318)
			(layers "F.Cu" "F.Mask" "F.Paste")
			(net "M_B_CPU0_SB_CS_N<1>")
		)
		(pad "K42" smd circle
			(at -4.055618 -22.845268 270)
			(size 0.4318 0.4318)
			(layers "F.Cu" "F.Mask" "F.Paste")
			(net "GND")
		)
		(pad "K44" smd circle
			(at -2.427732 -22.845268 270)
			(size 0.4318 0.4318)
			(layers "F.Cu" "F.Mask" "F.Paste")
			(net "M_B_CPU0_SB_CA<2>")
		)
		(pad "K47" smd circle
			(at 1.613916 -22.735286 270)
			(size 0.4318 0.4318)
			(layers "F.Cu" "F.Mask" "F.Paste")
			(net "M_B_CPU0_SA_CA<4>")
		)
		(pad "K49" smd circle
			(at 3.241802 -22.735286 270)
			(size 0.4318 0.4318)
			(layers "F.Cu" "F.Mask" "F.Paste")
			(net "GND")
		)
		(pad "K51" smd circle
			(at 4.869434 -22.735286 270)
			(size 0.4318 0.4318)
			(layers "F.Cu" "F.Mask" "F.Paste")
			(net "M_B_CPU0_SA_CS_N<0>")
		)
		(pad "K53" smd circle
			(at 6.49732 -22.735286 270)
			(size 0.4318 0.4318)
			(layers "F.Cu" "F.Mask" "F.Paste")
			(net "M_B_CPU0_SA_CB<5>")
		)
		(pad "K55" smd circle
			(at 8.124952 -22.735286 270)
			(size 0.4318 0.4318)
			(layers "F.Cu" "F.Mask" "F.Paste")
			(net "M_B_CPU0_SA_DQS_DP<4>")
		)
		(pad "K57" smd circle
			(at 9.752838 -22.735286 270)
			(size 0.4318 0.4318)
			(layers "F.Cu" "F.Mask" "F.Paste")
			(net "M_B_CPU0_SA_CB<0>")
		)
		(pad "K59" smd circle
			(at 11.380724 -22.735286 270)
			(size 0.4318 0.4318)
			(layers "F.Cu" "F.Mask" "F.Paste")
			(net "M_B_CPU0_SA_DQ<21>")
		)
		(pad "K61" smd circle
			(at 13.008356 -22.735286 270)
			(size 0.4318 0.4318)
			(layers "F.Cu" "F.Mask" "F.Paste")
			(net "M_B_CPU0_SA_DQS_DP<2>")
		)
	)
)
